(kicad_pcb
	(version 20260206)
	(generator "pcbnew")
	(generator_version "10.0")
	(general
		(thickness 1.6)
		(legacy_teardrops no)
	)
	(paper "A4")
	(title_block
		(title "Bryce Canyon_IOM_IOC_16318-2_OCP.brd")
		(comment 1 "Bryce Canyon / footprints 1396-1404 of 1605")
	)
	(layers
		(0 "F.Cu" signal "TOP")
		(4 "In1.Cu" signal "L2GND")
		(6 "In2.Cu" signal "L3")
		(8 "In3.Cu" signal "L4VCC")
		(10 "In4.Cu" signal "L5VCC")
		(12 "In5.Cu" signal "L6")
		(14 "In6.Cu" signal "L7GND")
		(2 "B.Cu" signal "BOTTOM")
		(9 "F.Adhes" user "F.Adhesive")
		(11 "B.Adhes" user "B.Adhesive")
		(13 "F.Paste" user "Package Geometry/Pastemask Top")
		(15 "B.Paste" user "Package Geometry/Pastemask Bottom")
		(5 "F.SilkS" user "Ref Des/Silkscreen Top")
		(7 "B.SilkS" user "Ref Des/Silkscreen Bottom")
		(1 "F.Mask" user "Board Geometry/Soldermask Top")
		(3 "B.Mask" user "Board Geometry/Soldermask Bottom")
		(17 "Dwgs.User" user "User.Drawings")
		(19 "Cmts.User" user "User.Comments")
		(21 "Eco1.User" user "User.Eco1")
		(23 "Eco2.User" user "User.Eco2")
		(25 "Edge.Cuts" user "Board Geometry/Outline")
		(27 "Margin" user)
		(31 "F.CrtYd" user "Package Geometry/Place Bound Top")
		(29 "B.CrtYd" user "Package Geometry/Place Bound Bottom")
		(35 "F.Fab" user "Ref Des/Assembly Top")
		(33 "B.Fab" user "Ref Des/Assembly Bottom")
	)
	(footprint ""
		(layer "B.Cu")
		(at 182.52186 -81.49844)
		(property "Reference" "C394"
			(at 0 0 0)
			(layer "B.SilkS")
			(hide yes)
			(effects
				(font
					(size 1.27 1.27)
				)
				(justify mirror)
			)
		)
		(property "Value" "SC1U16V2KX-7-GP"
			(at -1.7526 -1.6002 0)
			(unlocked yes)
			(layer "B.Fab")
			(hide yes)
			(effects
				(font
					(size 1.016 1.016)
					(thickness 0.1524)
				)
				(justify mirror)
			)
		)
		(property "Device Type" "C402-TO0D2H24"
			(at -1.7526 -3.1242 0)
			(unlocked yes)
			(layer "B.Fab")
			(hide yes)
			(effects
				(font
					(size 1.016 1.016)
					(thickness 0.1524)
				)
				(justify mirror)
			)
		)
		(duplicate_pad_numbers_are_jumpers no)
		(fp_rect
			(start 0.4826 0.889)
			(end -0.4826 -0.889)
			(stroke
				(width 0)
				(type default)
			)
			(fill no)
			(layer "B.CrtYd")
		)
		(fp_rect
			(start 0.4826 0.889)
			(end -0.4826 -0.889)
			(stroke
				(width 0)
				(type default)
			)
			(fill no)
			(layer "B.Fab")
		)
		(pad "1" smd custom
			(at 0 -0.4572 180)
			(size 0.1524 0.1524)
			(layers "B.Cu" "B.Mask" "B.Paste")
			(net "P0V975")
			(options
				(clearance outline)
				(anchor circle)
			)
			(primitives
				(gr_poly
					(pts
						(arc
							(start -0.254 -0.3048)
							(mid -0.325842 -0.275042)
							(end -0.3556 -0.2032)
						)
						(arc
							(start -0.3556 0.2032)
							(mid -0.325842 0.275042)
							(end -0.254 0.3048)
						)
						(arc
							(start 0.254 0.3048)
							(mid 0.325842 0.275042)
							(end 0.3556 0.2032)
						)
						(arc
							(start 0.3556 -0.2032)
							(mid 0.325842 -0.275042)
							(end 0.254 -0.3048)
						)
					)
					(width 0)
					(fill yes)
				)
			)
		)
		(pad "2" smd custom
			(at 0 0.4572 180)
			(size 0.1524 0.1524)
			(layers "B.Cu" "B.Mask" "B.Paste")
			(net "GND")
			(options
				(clearance outline)
				(anchor circle)
			)
			(primitives
				(gr_poly
					(pts
						(arc
							(start -0.254 -0.3048)
							(mid -0.325842 -0.275042)
							(end -0.3556 -0.2032)
						)
						(arc
							(start -0.3556 0.2032)
							(mid -0.325842 0.275042)
							(end -0.254 0.3048)
						)
						(arc
							(start 0.254 0.3048)
							(mid 0.325842 0.275042)
							(end 0.3556 0.2032)
						)
						(arc
							(start 0.3556 -0.2032)
							(mid 0.325842 -0.275042)
							(end 0.254 -0.3048)
						)
					)
					(width 0)
					(fill yes)
				)
			)
		)
	)
	(footprint ""
		(layer "B.Cu")
		(at 48.734726 -128.216406 180)
		(property "Reference" "R286"
			(at 0 0 0)
			(layer "B.SilkS")
			(hide yes)
			(effects
				(font
					(size 1.27 1.27)
				)
				(justify mirror)
			)
		)
		(property "Value" "0R2J-2-GP"
			(at -0.064008 -3.993896 180)
			(unlocked yes)
			(layer "B.Fab")
			(hide yes)
			(effects
				(font
					(size 1.016 1.016)
					(thickness 0.1524)
				)
				(justify mirror)
			)
		)
		(property "Device Type" "R402H16"
			(at -0.064008 -5.517896 180)
			(unlocked yes)
			(layer "B.Fab")
			(hide yes)
			(effects
				(font
					(size 1.016 1.016)
					(thickness 0.1524)
				)
				(justify mirror)
			)
		)
		(duplicate_pad_numbers_are_jumpers no)
		(fp_line
			(start 0.508 -0.9398)
			(end 0.508 0.9398)
			(stroke
				(width 0.1524)
				(type default)
			)
			(layer "B.SilkS")
		)
		(fp_line
			(start -0.508 -0.9398)
			(end 0.508 -0.9398)
			(stroke
				(width 0.1524)
				(type default)
			)
			(layer "B.SilkS")
		)
		(fp_rect
			(start 0.508 0.9398)
			(end -0.508 -0.9398)
			(stroke
				(width 0)
				(type default)
			)
			(fill no)
			(layer "B.CrtYd")
		)
		(fp_rect
			(start 0.508 0.9398)
			(end -0.508 -0.9398)
			(stroke
				(width 0)
				(type default)
			)
			(fill no)
			(layer "B.Fab")
		)
		(pad "1" smd custom
			(at 0 -0.4445)
			(size 0.1397 0.1397)
			(layers "B.Cu" "B.Mask" "B.Paste")
			(net "SCC_LOC_FULL_PWR_EN")
			(options
				(clearance outline)
				(anchor circle)
			)
			(primitives
				(gr_poly
					(pts
						(arc
							(start -0.1778 0.2794)
							(mid -0.249642 0.249642)
							(end -0.2794 0.1778)
						)
						(arc
							(start -0.2794 -0.1778)
							(mid -0.249642 -0.249642)
							(end -0.1778 -0.2794)
						)
						(arc
							(start 0.1778 -0.2794)
							(mid 0.249642 -0.249642)
							(end 0.2794 -0.1778)
						)
						(arc
							(start 0.2794 0.1778)
							(mid 0.249642 0.249642)
							(end 0.1778 0.2794)
						)
					)
					(width 0)
					(fill yes)
				)
			)
		)
		(pad "2" smd custom
			(at 0 0.4445)
			(size 0.1397 0.1397)
			(layers "B.Cu" "B.Mask" "B.Paste")
			(net "SCC_LOC_FULLPWR_EN")
			(options
				(clearance outline)
				(anchor circle)
			)
			(primitives
				(gr_poly
					(pts
						(arc
							(start -0.1778 0.2794)
							(mid -0.249642 0.249642)
							(end -0.2794 0.1778)
						)
						(arc
							(start -0.2794 -0.1778)
							(mid -0.249642 -0.249642)
							(end -0.1778 -0.2794)
						)
						(arc
							(start 0.1778 -0.2794)
							(mid 0.249642 -0.249642)
							(end 0.2794 -0.1778)
						)
						(arc
							(start 0.2794 0.1778)
							(mid 0.249642 0.249642)
							(end 0.1778 0.2794)
						)
					)
					(width 0)
					(fill yes)
				)
			)
		)
	)
	(footprint ""
		(layer "B.Cu")
		(at 40.4876 -126.5682)
		(property "Reference" "TP84"
			(at 0 0 0)
			(layer "B.SilkS")
			(hide yes)
			(effects
				(font
					(size 1.27 1.27)
				)
				(justify mirror)
			)
		)
		(property "Value" "TPAD28-2-GP"
			(at 0.0127 -1.6637 0)
			(unlocked yes)
			(layer "B.Fab")
			(hide yes)
			(effects
				(font
					(size 1.016 1.016)
					(thickness 0.1524)
				)
				(justify mirror)
			)
		)
		(property "Device Type" "TPAD28"
			(at 0.0127 -3.1877 0)
			(unlocked yes)
			(layer "B.Fab")
			(hide yes)
			(effects
				(font
					(size 1.016 1.016)
					(thickness 0.1524)
				)
				(justify mirror)
			)
		)
		(duplicate_pad_numbers_are_jumpers no)
		(fp_poly
			(pts
				(arc
					(start 0.3556 0)
					(mid -0.3556 0)
					(end 0.3556 0)
				)
			)
			(stroke
				(width 0)
				(type default)
			)
			(fill no)
			(layer "B.CrtYd")
		)
		(fp_poly
			(pts
				(arc
					(start 0.6096 0)
					(mid -0.6096 0)
					(end 0.6096 0)
				)
			)
			(stroke
				(width 0)
				(type default)
			)
			(fill no)
			(layer "B.Fab")
		)
		(pad "1" smd circle
			(at 0 0 180)
			(size 0.7112 0.7112)
			(layers "B.Cu" "B.Mask" "B.Paste")
			(net "FM_BMC_RESET_N")
		)
	)
	(footprint ""
		(layer "B.Cu")
		(at 181.487826 -69.878956)
		(property "Reference" "TP127"
			(at 0 0 0)
			(layer "B.SilkS")
			(hide yes)
			(effects
				(font
					(size 1.27 1.27)
				)
				(justify mirror)
			)
		)
		(property "Value" "TPAD28-2-GP"
			(at 0.0127 -1.6637 0)
			(unlocked yes)
			(layer "B.Fab")
			(hide yes)
			(effects
				(font
					(size 1.016 1.016)
					(thickness 0.1524)
				)
				(justify mirror)
			)
		)
		(property "Device Type" "TPAD28"
			(at 0.0127 -3.1877 0)
			(unlocked yes)
			(layer "B.Fab")
			(hide yes)
			(effects
				(font
					(size 1.016 1.016)
					(thickness 0.1524)
				)
				(justify mirror)
			)
		)
		(duplicate_pad_numbers_are_jumpers no)
		(fp_poly
			(pts
				(arc
					(start 0.3556 0)
					(mid -0.3556 0)
					(end 0.3556 0)
				)
			)
			(stroke
				(width 0)
				(type default)
			)
			(fill no)
			(layer "B.CrtYd")
		)
		(fp_poly
			(pts
				(arc
					(start 0.6096 0)
					(mid -0.6096 0)
					(end 0.6096 0)
				)
			)
			(stroke
				(width 0)
				(type default)
			)
			(fill no)
			(layer "B.Fab")
		)
		(pad "1" smd circle
			(at 0 0 180)
			(size 0.7112 0.7112)
			(layers "B.Cu" "B.Mask" "B.Paste")
			(net "IOC_GPIO_34")
		)
	)
	(footprint ""
		(layer "B.Cu")
		(at 197.20814 -61.4553 90)
		(property "Reference" "C385"
			(at 0 0 90)
			(layer "B.SilkS")
			(hide yes)
			(effects
				(font
					(size 1.27 1.27)
				)
				(justify mirror)
			)
		)
		(property "Value" "SC10U6D3V5KX-4GP"
			(at 0.0762 -6.1214 90)
			(unlocked yes)
			(layer "B.Fab")
			(hide yes)
			(effects
				(font
					(size 1.016 1.016)
					(thickness 0.1524)
				)
				(justify mirror)
			)
		)
		(property "Device Type" "C805H58"
			(at 0.0762 -8.1534 90)
			(unlocked yes)
			(layer "B.Fab")
			(hide yes)
			(effects
				(font
					(size 1.016 1.016)
					(thickness 0.1524)
				)
				(justify mirror)
			)
		)
		(duplicate_pad_numbers_are_jumpers no)
		(fp_line
			(start -0.635 0)
			(end 0.635 0)
			(stroke
				(width 0.508)
				(type default)
			)
			(layer "B.SilkS")
		)
		(fp_rect
			(start 0.9652 1.778)
			(end -0.9652 -1.778)
			(stroke
				(width 0)
				(type default)
			)
			(fill no)
			(layer "B.CrtYd")
		)
		(fp_poly
			(pts
				(xy 0.9652 -1.778) (xy -0.9652 -1.778) (xy -0.9652 1.778) (xy 0.9652 1.778)
			)
			(stroke
				(width 0)
				(type default)
			)
			(fill no)
			(layer "B.Fab")
		)
		(pad "1" smd rect
			(at 0 -0.9652 270)
			(size 1.397 1.143)
			(layers "B.Cu" "B.Mask" "B.Paste")
			(net "P0V975")
		)
		(pad "2" smd rect
			(at 0 0.9652 270)
			(size 1.397 1.143)
			(layers "B.Cu" "B.Mask" "B.Paste")
			(net "GND")
		)
	)
	(footprint ""
		(layer "B.Cu")
		(at 180.2384 -76.0476)
		(property "Reference" "TP88"
			(at 0 0 0)
			(layer "B.SilkS")
			(hide yes)
			(effects
				(font
					(size 1.27 1.27)
				)
				(justify mirror)
			)
		)
		(property "Value" "TPAD28-2-GP"
			(at 0.0127 -1.6637 0)
			(unlocked yes)
			(layer "B.Fab")
			(hide yes)
			(effects
				(font
					(size 1.016 1.016)
					(thickness 0.1524)
				)
				(justify mirror)
			)
		)
		(property "Device Type" "TPAD28"
			(at 0.0127 -3.1877 0)
			(unlocked yes)
			(layer "B.Fab")
			(hide yes)
			(effects
				(font
					(size 1.016 1.016)
					(thickness 0.1524)
				)
				(justify mirror)
			)
		)
		(duplicate_pad_numbers_are_jumpers no)
		(fp_poly
			(pts
				(arc
					(start 0.3556 0)
					(mid -0.3556 0)
					(end 0.3556 0)
				)
			)
			(stroke
				(width 0)
				(type default)
			)
			(fill no)
			(layer "B.CrtYd")
		)
		(fp_poly
			(pts
				(arc
					(start 0.6096 0)
					(mid -0.6096 0)
					(end 0.6096 0)
				)
			)
			(stroke
				(width 0)
				(type default)
			)
			(fill no)
			(layer "B.Fab")
		)
		(pad "1" smd circle
			(at 0 0 180)
			(size 0.7112 0.7112)
			(layers "B.Cu" "B.Mask" "B.Paste")
			(net "IOC_GPIO_0")
		)
	)
	(footprint ""
		(layer "B.Cu")
		(at 203.327 -78.613 90)
		(property "Reference" "C376"
			(at 0 0 90)
			(layer "B.SilkS")
			(hide yes)
			(effects
				(font
					(size 1.27 1.27)
				)
				(justify mirror)
			)
		)
		(property "Value" "SCD1U6D3V1KX-GP"
			(at 2.8321 -1.7399 90)
			(unlocked yes)
			(layer "B.Fab")
			(hide yes)
			(effects
				(font
					(size 1.016 1.016)
					(thickness 0.1524)
				)
				(justify mirror)
			)
		)
		(property "Device Type" "C0201H13"
			(at 2.8321 -3.2639 90)
			(unlocked yes)
			(layer "B.Fab")
			(hide yes)
			(effects
				(font
					(size 1.016 1.016)
					(thickness 0.1524)
				)
				(justify mirror)
			)
		)
		(duplicate_pad_numbers_are_jumpers no)
		(fp_rect
			(start 0.2794 0.6477)
			(end -0.2794 -0.6477)
			(stroke
				(width 0)
				(type default)
			)
			(fill no)
			(layer "B.CrtYd")
		)
		(fp_rect
			(start 0.2794 0.6477)
			(end -0.2794 -0.6477)
			(stroke
				(width 0)
				(type default)
			)
			(fill no)
			(layer "B.Fab")
		)
		(pad "1" smd custom
			(at 0 -0.2794 270)
			(size 0.0762 0.0762)
			(layers "B.Cu" "B.Mask" "B.Paste")
			(net "SAS0_AVDD")
			(options
				(clearance outline)
				(anchor circle)
			)
			(primitives
				(gr_poly
					(pts
						(arc
							(start 0.1524 0.127)
							(mid 0.137521 0.162921)
							(end 0.1016 0.1778)
						)
						(arc
							(start -0.1016 0.1778)
							(mid -0.137521 0.162921)
							(end -0.1524 0.127)
						)
						(arc
							(start -0.1524 -0.127)
							(mid -0.137521 -0.162921)
							(end -0.1016 -0.1778)
						)
						(arc
							(start 0.1016 -0.1778)
							(mid 0.137521 -0.162921)
							(end 0.1524 -0.127)
						)
					)
					(width 0)
					(fill yes)
				)
			)
		)
		(pad "2" smd custom
			(at 0 0.2794 270)
			(size 0.0762 0.0762)
			(layers "B.Cu" "B.Mask" "B.Paste")
			(net "GND")
			(options
				(clearance outline)
				(anchor circle)
			)
			(primitives
				(gr_poly
					(pts
						(arc
							(start 0.1524 0.127)
							(mid 0.137521 0.162921)
							(end 0.1016 0.1778)
						)
						(arc
							(start -0.1016 0.1778)
							(mid -0.137521 0.162921)
							(end -0.1524 0.127)
						)
						(arc
							(start -0.1524 -0.127)
							(mid -0.137521 -0.162921)
							(end -0.1016 -0.1778)
						)
						(arc
							(start 0.1016 -0.1778)
							(mid 0.137521 -0.162921)
							(end 0.1524 -0.127)
						)
					)
					(width 0)
					(fill yes)
				)
			)
		)
	)
	(footprint ""
		(layer "B.Cu")
		(at 60.22594 -152.94864 -90)
		(property "Reference" "R399"
			(at 0 0 90)
			(layer "B.SilkS")
			(hide yes)
			(effects
				(font
					(size 1.27 1.27)
				)
				(justify mirror)
			)
		)
		(property "Value" "4K7R2F-GP"
			(at -0.064008 -3.993896 270)
			(unlocked yes)
			(layer "B.Fab")
			(hide yes)
			(effects
				(font
					(size 1.016 1.016)
					(thickness 0.1524)
				)
				(justify mirror)
			)
		)
		(property "Device Type" "R402H16"
			(at -0.064008 -5.517896 270)
			(unlocked yes)
			(layer "B.Fab")
			(hide yes)
			(effects
				(font
					(size 1.016 1.016)
					(thickness 0.1524)
				)
				(justify mirror)
			)
		)
		(duplicate_pad_numbers_are_jumpers no)
		(fp_line
			(start -0.508 -0.9398)
			(end 0.508 -0.9398)
			(stroke
				(width 0.1524)
				(type default)
			)
			(layer "B.SilkS")
		)
		(fp_line
			(start 0.508 -0.9398)
			(end 0.508 0.9398)
			(stroke
				(width 0.1524)
				(type default)
			)
			(layer "B.SilkS")
		)
		(fp_rect
			(start 0.508 0.9398)
			(end -0.508 -0.9398)
			(stroke
				(width 0)
				(type default)
			)
			(fill no)
			(layer "B.CrtYd")
		)
		(fp_rect
			(start 0.508 0.9398)
			(end -0.508 -0.9398)
			(stroke
				(width 0)
				(type default)
			)
			(fill no)
			(layer "B.Fab")
		)
		(pad "1" smd custom
			(at 0 -0.4445 90)
			(size 0.1397 0.1397)
			(layers "B.Cu" "B.Mask" "B.Paste")
			(net "GND")
			(options
				(clearance outline)
				(anchor circle)
			)
			(primitives
				(gr_poly
					(pts
						(arc
							(start -0.1778 0.2794)
							(mid -0.249642 0.249642)
							(end -0.2794 0.1778)
						)
						(arc
							(start -0.2794 -0.1778)
							(mid -0.249642 -0.249642)
							(end -0.1778 -0.2794)
						)
						(arc
							(start 0.1778 -0.2794)
							(mid 0.249642 -0.249642)
							(end 0.2794 -0.1778)
						)
						(arc
							(start 0.2794 0.1778)
							(mid 0.249642 0.249642)
							(end 0.1778 0.2794)
						)
					)
					(width 0)
					(fill yes)
				)
			)
		)
		(pad "2" smd custom
			(at 0 0.4445 90)
			(size 0.1397 0.1397)
			(layers "B.Cu" "B.Mask" "B.Paste")
			(net "MAC2_TXD3")
			(options
				(clearance outline)
				(anchor circle)
			)
			(primitives
				(gr_poly
					(pts
						(arc
							(start -0.1778 0.2794)
							(mid -0.249642 0.249642)
							(end -0.2794 0.1778)
						)
						(arc
							(start -0.2794 -0.1778)
							(mid -0.249642 -0.249642)
							(end -0.1778 -0.2794)
						)
						(arc
							(start 0.1778 -0.2794)
							(mid 0.249642 -0.249642)
							(end 0.2794 -0.1778)
						)
						(arc
							(start 0.2794 0.1778)
							(mid 0.249642 0.249642)
							(end 0.1778 0.2794)
						)
					)
					(width 0)
					(fill yes)
				)
			)
		)
	)
	(footprint ""
		(layer "B.Cu")
		(at 201.860404 -92.851224 180)
		(property "Reference" "C356"
			(at 0 0 0)
			(layer "B.SilkS")
			(hide yes)
			(effects
				(font
					(size 1.27 1.27)
				)
				(justify mirror)
			)
		)
		(property "Value" "SC22U6D3V3MX-9-GP-U"
			(at 0 -2.8194 180)
			(unlocked yes)
			(layer "B.Fab")
			(hide yes)
			(effects
				(font
					(size 1.016 1.016)
					(thickness 0.1524)
				)
				(justify mirror)
			)
		)
		(property "Device Type" "C603H40"
			(at 0 -4.3434 180)
			(unlocked yes)
			(layer "B.Fab")
			(hide yes)
			(effects
				(font
					(size 1.016 1.016)
					(thickness 0.1524)
				)
				(justify mirror)
			)
		)
		(duplicate_pad_numbers_are_jumpers no)
		(fp_line
			(start -0.508 0)
			(end 0.508 0)
			(stroke
				(width 0.2032)
				(type default)
			)
			(layer "B.SilkS")
		)
		(fp_rect
			(start 0.5842 1.3335)
			(end -0.5842 -1.3335)
			(stroke
				(width 0)
				(type default)
			)
			(fill no)
			(layer "B.CrtYd")
		)
		(fp_rect
			(start 0.5842 1.3335)
			(end -0.5842 -1.3335)
			(stroke
				(width 0)
				(type default)
			)
			(fill no)
			(layer "B.Fab")
		)
		(pad "1" smd custom
			(at 0 -0.762)
			(size 0.2159 0.2159)
			(layers "B.Cu" "B.Mask" "B.Paste")
			(net "PCE_VDDH")
			(options
				(clearance outline)
				(anchor circle)
			)
			(primitives
				(gr_poly
					(pts
						(arc
							(start -0.3302 0.4318)
							(mid -0.402042 0.402042)
							(end -0.4318 0.3302)
						)
						(arc
							(start -0.4318 -0.3302)
							(mid -0.402042 -0.402042)
							(end -0.3302 -0.4318)
						)
						(arc
							(start 0.3302 -0.4318)
							(mid 0.402042 -0.402042)
							(end 0.4318 -0.3302)
						)
						(arc
							(start 0.4318 0.3302)
							(mid 0.402042 0.402042)
							(end 0.3302 0.4318)
						)
					)
					(width 0)
					(fill yes)
				)
			)
		)
		(pad "2" smd custom
			(at 0 0.762)
			(size 0.2159 0.2159)
			(layers "B.Cu" "B.Mask" "B.Paste")
			(net "GND")
			(options
				(clearance outline)
				(anchor circle)
			)
			(primitives
				(gr_poly
					(pts
						(arc
							(start -0.3302 0.4318)
							(mid -0.402042 0.402042)
							(end -0.4318 0.3302)
						)
						(arc
							(start -0.4318 -0.3302)
							(mid -0.402042 -0.402042)
							(end -0.3302 -0.4318)
						)
						(arc
							(start 0.3302 -0.4318)
							(mid 0.402042 -0.402042)
							(end 0.4318 -0.3302)
						)
						(arc
							(start 0.4318 0.3302)
							(mid 0.402042 0.402042)
							(end 0.3302 0.4318)
						)
					)
					(width 0)
					(fill yes)
				)
			)
		)
	)
)
